# S9S_MB_2U (Grand Teton) — schematic netlist excerpt (pin names and nets, part order shuffled) for the footprints in the layout excerpt that follows; sources: Cadence DE-HDL packaged netlist, KiCad conversion of 03242023_DA0F0TMBIJ0_F0T_Motherboard_J_brd_V01_OCP.brd

R3280  Q_RES  1K 1% EMPTY  pkg 0402LF  page 166 : A = P3V3_AUX ; B = FM_P2E_EQB1
PR1  Q_RES  0 5% CHIP  pkg 0402LF  page 282 : A = GND ; B = GND
ME27  ME_DUMMY_SYMBOL  CBS_3X558-8 EMPTY  pkg CBS_3X558-8  page 312

(kicad_pcb
	(version 20260206)
	(generator "pcbnew")
	(generator_version "10.0")
	(general
		(thickness 1.6)
		(legacy_teardrops no)
	)
	(paper "A4")
	(title_block
		(title "03242023_DA0F0TMBIJ0_F0T_Motherboard_J_brd_V01_OCP.brd")
		(comment 1 "Grand Teton / footprints 1976-1978 of 6105")
	)
	(layers
		(0 "F.Cu" signal "TOP")
		(4 "In1.Cu" signal "GND")
		(6 "In2.Cu" signal "IN1")
		(8 "In3.Cu" signal "GND1")
		(10 "In4.Cu" signal "IN2")
		(12 "In5.Cu" signal "GND2")
		(14 "In6.Cu" signal "IN3")
		(16 "In7.Cu" signal "GND3")
		(18 "In8.Cu" signal "VCC")
		(20 "In9.Cu" signal "VCC1")
		(22 "In10.Cu" signal "GND4")
		(24 "In11.Cu" signal "IN4")
		(26 "In12.Cu" signal "GND5")
		(28 "In13.Cu" signal "IN5")
		(30 "In14.Cu" signal "GND6")
		(32 "In15.Cu" signal "IN6")
		(34 "In16.Cu" signal "GND7")
		(2 "B.Cu" signal "BOTTOM")
		(9 "F.Adhes" user "F.Adhesive")
		(11 "B.Adhes" user "B.Adhesive")
		(13 "F.Paste" user "Package Geometry/Pastemask Top")
		(15 "B.Paste" user "Package Geometry/Pastemask Bottom")
		(5 "F.SilkS" user "Ref Des/Silkscreen Top")
		(7 "B.SilkS" user "Ref Des/Silkscreen Bottom")
		(1 "F.Mask" user "Board Geometry/Soldermask Top")
		(3 "B.Mask" user "Board Geometry/Soldermask Bottom")
		(17 "Dwgs.User" user "User.Drawings")
		(19 "Cmts.User" user "User.Comments")
		(21 "Eco1.User" user "User.Eco1")
		(23 "Eco2.User" user "User.Eco2")
		(25 "Edge.Cuts" user "Board Geometry/Outline")
		(27 "Margin" user)
		(31 "F.CrtYd" user "Package Geometry/Place Bound Top")
		(29 "B.CrtYd" user "Package Geometry/Place Bound Bottom")
		(35 "F.Fab" user "Ref Des/Assembly Top")
		(33 "B.Fab" user "Ref Des/Assembly Bottom")
	)
	(footprint ""
		(layer "F.Cu")
		(at 27.628596 -395.374876 180)
		(property "Reference" "R3280"
			(at 0 0 180)
			(layer "F.SilkS")
			(hide yes)
			(effects
				(font
					(size 1.27 1.27)
				)
			)
		)
		(property "Value" ""
			(at 0 0 180)
			(layer "F.Fab")
			(effects
				(font
					(size 1.27 1.27)
				)
			)
		)
		(duplicate_pad_numbers_are_jumpers no)
		(fp_line
			(start 0.7874 0.4064)
			(end -0.7874 0.4064)
			(stroke
				(width 0.1524)
				(type default)
			)
			(layer "F.SilkS")
		)
		(fp_line
			(start 0.7874 -0.4064)
			(end 0.7874 0.4064)
			(stroke
				(width 0.1524)
				(type default)
			)
			(layer "F.SilkS")
		)
		(fp_line
			(start -0.7874 0.4064)
			(end -0.7874 -0.4064)
			(stroke
				(width 0.1524)
				(type default)
			)
			(layer "F.SilkS")
		)
		(fp_line
			(start -0.7874 -0.4064)
			(end 0.7874 -0.4064)
			(stroke
				(width 0.1524)
				(type default)
			)
			(layer "F.SilkS")
		)
		(fp_line
			(start 0.67945 0.3048)
			(end 0.120396 0.3048)
			(stroke
				(width 0.1)
				(type default)
			)
			(layer "F.Fab")
		)
		(fp_line
			(start 0.67945 -0.3048)
			(end 0.67945 0.3048)
			(stroke
				(width 0.1)
				(type default)
			)
			(layer "F.Fab")
		)
		(fp_line
			(start 0.12065 -0.2794)
			(end 0.12065 -0.3048)
			(stroke
				(width 0.1)
				(type default)
			)
			(layer "F.Fab")
		)
		(fp_line
			(start 0.12065 -0.3048)
			(end 0.67945 -0.3048)
			(stroke
				(width 0.1)
				(type default)
			)
			(layer "F.Fab")
		)
		(fp_line
			(start 0.120396 0.3048)
			(end 0.120396 0.2794)
			(stroke
				(width 0.1)
				(type default)
			)
			(layer "F.Fab")
		)
		(fp_line
			(start 0.120396 0.2794)
			(end -0.12065 0.2794)
			(stroke
				(width 0.1)
				(type default)
			)
			(layer "F.Fab")
		)
		(fp_line
			(start -0.12065 0.3048)
			(end -0.67945 0.3048)
			(stroke
				(width 0.1)
				(type default)
			)
			(layer "F.Fab")
		)
		(fp_line
			(start -0.12065 0.2794)
			(end -0.12065 0.3048)
			(stroke
				(width 0.1)
				(type default)
			)
			(layer "F.Fab")
		)
		(fp_line
			(start -0.12065 -0.2794)
			(end 0.12065 -0.2794)
			(stroke
				(width 0.1)
				(type default)
			)
			(layer "F.Fab")
		)
		(fp_line
			(start -0.12065 -0.305054)
			(end -0.12065 -0.2794)
			(stroke
				(width 0.1)
				(type default)
			)
			(layer "F.Fab")
		)
		(fp_line
			(start -0.67945 0.3048)
			(end -0.67945 -0.305054)
			(stroke
				(width 0.1)
				(type default)
			)
			(layer "F.Fab")
		)
		(fp_line
			(start -0.67945 -0.305054)
			(end -0.12065 -0.305054)
			(stroke
				(width 0.1)
				(type default)
			)
			(layer "F.Fab")
		)
		(pad "1" smd circle
			(at -0.40005 0 180)
			(size 0 0)
			(layers "F.Cu" "F.Mask" "F.Paste")
			(net "P3V3_AUX")
		)
		(pad "2" smd circle
			(at 0.40005 0 180)
			(size 0 0)
			(layers "F.Cu" "F.Mask" "F.Paste")
			(net "FM_P2E_EQB1")
		)
	)
	(footprint ""
		(layer "F.Cu")
		(at 432.757072 -177.903124 -90)
		(property "Reference" "PR1"
			(at 0 0 270)
			(layer "F.SilkS")
			(hide yes)
			(effects
				(font
					(size 1.27 1.27)
				)
			)
		)
		(property "Value" ""
			(at 0 0 270)
			(layer "F.Fab")
			(effects
				(font
					(size 1.27 1.27)
				)
			)
		)
		(duplicate_pad_numbers_are_jumpers no)
		(fp_line
			(start -0.7874 0.4064)
			(end -0.7874 -0.4064)
			(stroke
				(width 0.1524)
				(type default)
			)
			(layer "F.SilkS")
		)
		(fp_line
			(start 0.7874 0.4064)
			(end -0.7874 0.4064)
			(stroke
				(width 0.1524)
				(type default)
			)
			(layer "F.SilkS")
		)
		(fp_line
			(start -0.7874 -0.4064)
			(end 0.7874 -0.4064)
			(stroke
				(width 0.1524)
				(type default)
			)
			(layer "F.SilkS")
		)
		(fp_line
			(start 0.7874 -0.4064)
			(end 0.7874 0.4064)
			(stroke
				(width 0.1524)
				(type default)
			)
			(layer "F.SilkS")
		)
		(fp_line
			(start -0.67945 0.3048)
			(end -0.67945 -0.305054)
			(stroke
				(width 0.1)
				(type default)
			)
			(layer "F.Fab")
		)
		(fp_line
			(start -0.12065 0.3048)
			(end -0.67945 0.3048)
			(stroke
				(width 0.1)
				(type default)
			)
			(layer "F.Fab")
		)
		(fp_line
			(start 0.120396 0.3048)
			(end 0.120396 0.2794)
			(stroke
				(width 0.1)
				(type default)
			)
			(layer "F.Fab")
		)
		(fp_line
			(start 0.67945 0.3048)
			(end 0.120396 0.3048)
			(stroke
				(width 0.1)
				(type default)
			)
			(layer "F.Fab")
		)
		(fp_line
			(start -0.12065 0.2794)
			(end -0.12065 0.3048)
			(stroke
				(width 0.1)
				(type default)
			)
			(layer "F.Fab")
		)
		(fp_line
			(start 0.120396 0.2794)
			(end -0.12065 0.2794)
			(stroke
				(width 0.1)
				(type default)
			)
			(layer "F.Fab")
		)
		(fp_line
			(start -0.12065 -0.2794)
			(end 0.12065 -0.2794)
			(stroke
				(width 0.1)
				(type default)
			)
			(layer "F.Fab")
		)
		(fp_line
			(start 0.12065 -0.2794)
			(end 0.12065 -0.3048)
			(stroke
				(width 0.1)
				(type default)
			)
			(layer "F.Fab")
		)
		(fp_line
			(start 0.12065 -0.3048)
			(end 0.67945 -0.3048)
			(stroke
				(width 0.1)
				(type default)
			)
			(layer "F.Fab")
		)
		(fp_line
			(start 0.67945 -0.3048)
			(end 0.67945 0.3048)
			(stroke
				(width 0.1)
				(type default)
			)
			(layer "F.Fab")
		)
		(fp_line
			(start -0.67945 -0.305054)
			(end -0.12065 -0.305054)
			(stroke
				(width 0.1)
				(type default)
			)
			(layer "F.Fab")
		)
		(fp_line
			(start -0.12065 -0.305054)
			(end -0.12065 -0.2794)
			(stroke
				(width 0.1)
				(type default)
			)
			(layer "F.Fab")
		)
		(pad "1" smd circle
			(at -0.40005 0 270)
			(size 0 0)
			(layers "F.Cu" "F.Mask" "F.Paste")
			(net "GND")
		)
		(pad "2" smd circle
			(at 0.40005 0 270)
			(size 0 0)
			(layers "F.Cu" "F.Mask" "F.Paste")
			(net "GND")
		)
	)
	(footprint ""
		(layer "F.Cu")
		(at 249.034046 -540.634682 -90)
		(property "Reference" "ME27"
			(at 0.0254 -3.851148 270)
			(unlocked yes)
			(layer "F.SilkS")
			(effects
				(font
					(size 0.7874 0.5842)
					(thickness 0.1524)
				)
				(justify left)
			)
		)
		(property "Value" ""
			(at 0 0 270)
			(layer "F.Fab")
			(effects
				(font
					(size 1.27 1.27)
				)
			)
		)
		(duplicate_pad_numbers_are_jumpers no)
		(zone
			(layer "F.Cu")
			(hatch none 0.5)
			(connect_pads
				(clearance 0)
			)
			(min_thickness 0.25)
			(keepout
				(tracks allowed)
				(vias allowed)
				(pads allowed)
				(copperpour allowed)
				(footprints not_allowed)
			)
			(placement
				(enabled no)
				(sheetname "")
			)
			(fill
				(thermal_gap 0.5)
				(thermal_bridge_width 0.5)
				(island_removal_mode 0)
			)
			(polygon
				(pts
					(xy 249.034046 -540.634682) (xy 249.034046 18.165318) (xy 252.03404 18.165318) (xy 252.03404 -540.634682)
				)
			)
		)
	)
)
